# SCM (Grand Teton) — schematic netlist excerpt (pin names and nets, part order shuffled) for the footprints in the layout excerpt that follows; sources: Cadence DE-HDL packaged netlist, KiCad conversion of 12092022_DA0F0TMDCD0_F0T_Management_Board_D_brd_V3_OCP.brd

C180  Q_CAP  0.1UF 25V 10% X7R  pkg 0402  page 13 : A = P3V3_LDO ; B = GND
R39  Q_RES  0 5% CHIP  pkg 0402LF  page 30 : A = SPA_SOUT_SW_BUF_R ; B = SPA_SOUT_SW_BUF

(kicad_pcb
	(version 20260206)
	(generator "pcbnew")
	(generator_version "10.0")
	(general
		(thickness 1.6)
		(legacy_teardrops no)
	)
	(paper "A4")
	(title_block
		(title "12092022_DA0F0TMDCD0_F0T_Management_Board_D_brd_V3_OCP.brd")
		(comment 1 "Grand Teton / footprints 590-591 of 1440")
	)
	(layers
		(0 "F.Cu" signal "TOP")
		(4 "In1.Cu" signal "GND")
		(6 "In2.Cu" signal "IN1")
		(8 "In3.Cu" signal "GND1")
		(10 "In4.Cu" signal "IN2")
		(12 "In5.Cu" signal "VCC")
		(14 "In6.Cu" signal "VCC1")
		(16 "In7.Cu" signal "IN3")
		(18 "In8.Cu" signal "GND2")
		(20 "In9.Cu" signal "IN4")
		(22 "In10.Cu" signal "GND3")
		(2 "B.Cu" signal "BOTTOM")
		(9 "F.Adhes" user "F.Adhesive")
		(11 "B.Adhes" user "B.Adhesive")
		(13 "F.Paste" user "Package Geometry/Pastemask Top")
		(15 "B.Paste" user "Package Geometry/Pastemask Bottom")
		(5 "F.SilkS" user "Ref Des/Silkscreen Top")
		(7 "B.SilkS" user "Ref Des/Silkscreen Bottom")
		(1 "F.Mask" user "Board Geometry/Soldermask Top")
		(3 "B.Mask" user "Board Geometry/Soldermask Bottom")
		(17 "Dwgs.User" user "User.Drawings")
		(19 "Cmts.User" user "User.Comments")
		(21 "Eco1.User" user "User.Eco1")
		(23 "Eco2.User" user "User.Eco2")
		(25 "Edge.Cuts" user "Board Geometry/Outline")
		(27 "Margin" user)
		(31 "F.CrtYd" user "Package Geometry/Place Bound Top")
		(29 "B.CrtYd" user "Package Geometry/Place Bound Bottom")
		(35 "F.Fab" user "Ref Des/Assembly Top")
		(33 "B.Fab" user "Ref Des/Assembly Bottom")
	)
	(footprint ""
		(layer "F.Cu")
		(at 25.781 -65.913 -90)
		(property "Reference" "R39"
			(at 0 0 270)
			(layer "F.SilkS")
			(hide yes)
			(effects
				(font
					(size 1.27 1.27)
				)
			)
		)
		(property "Value" ""
			(at 0 0 270)
			(layer "F.Fab")
			(effects
				(font
					(size 1.27 1.27)
				)
			)
		)
		(duplicate_pad_numbers_are_jumpers no)
		(fp_line
			(start -0.7874 0.4064)
			(end -0.7874 -0.4064)
			(stroke
				(width 0.1524)
				(type default)
			)
			(layer "F.SilkS")
		)
		(fp_line
			(start 0.7874 0.4064)
			(end -0.7874 0.4064)
			(stroke
				(width 0.1524)
				(type default)
			)
			(layer "F.SilkS")
		)
		(fp_line
			(start -0.7874 -0.4064)
			(end 0.7874 -0.4064)
			(stroke
				(width 0.1524)
				(type default)
			)
			(layer "F.SilkS")
		)
		(fp_line
			(start 0.7874 -0.4064)
			(end 0.7874 0.4064)
			(stroke
				(width 0.1524)
				(type default)
			)
			(layer "F.SilkS")
		)
		(fp_line
			(start -0.67945 0.3048)
			(end -0.67945 -0.305054)
			(stroke
				(width 0.1)
				(type default)
			)
			(layer "F.Fab")
		)
		(fp_line
			(start -0.12065 0.3048)
			(end -0.67945 0.3048)
			(stroke
				(width 0.1)
				(type default)
			)
			(layer "F.Fab")
		)
		(fp_line
			(start 0.120396 0.3048)
			(end 0.120396 0.2794)
			(stroke
				(width 0.1)
				(type default)
			)
			(layer "F.Fab")
		)
		(fp_line
			(start 0.67945 0.3048)
			(end 0.120396 0.3048)
			(stroke
				(width 0.1)
				(type default)
			)
			(layer "F.Fab")
		)
		(fp_line
			(start -0.12065 0.2794)
			(end -0.12065 0.3048)
			(stroke
				(width 0.1)
				(type default)
			)
			(layer "F.Fab")
		)
		(fp_line
			(start 0.120396 0.2794)
			(end -0.12065 0.2794)
			(stroke
				(width 0.1)
				(type default)
			)
			(layer "F.Fab")
		)
		(fp_line
			(start -0.12065 -0.2794)
			(end 0.12065 -0.2794)
			(stroke
				(width 0.1)
				(type default)
			)
			(layer "F.Fab")
		)
		(fp_line
			(start 0.12065 -0.2794)
			(end 0.12065 -0.3048)
			(stroke
				(width 0.1)
				(type default)
			)
			(layer "F.Fab")
		)
		(fp_line
			(start 0.12065 -0.3048)
			(end 0.67945 -0.3048)
			(stroke
				(width 0.1)
				(type default)
			)
			(layer "F.Fab")
		)
		(fp_line
			(start 0.67945 -0.3048)
			(end 0.67945 0.3048)
			(stroke
				(width 0.1)
				(type default)
			)
			(layer "F.Fab")
		)
		(fp_line
			(start -0.67945 -0.305054)
			(end -0.12065 -0.305054)
			(stroke
				(width 0.1)
				(type default)
			)
			(layer "F.Fab")
		)
		(fp_line
			(start -0.12065 -0.305054)
			(end -0.12065 -0.2794)
			(stroke
				(width 0.1)
				(type default)
			)
			(layer "F.Fab")
		)
		(pad "1" smd circle
			(at -0.40005 0 270)
			(size 0 0)
			(layers "F.Cu" "F.Mask" "F.Paste")
			(net "SPA_SOUT_SW_BUF_R")
		)
		(pad "2" smd circle
			(at 0.40005 0 270)
			(size 0 0)
			(layers "F.Cu" "F.Mask" "F.Paste")
			(net "SPA_SOUT_SW_BUF")
		)
	)
	(footprint ""
		(layer "F.Cu")
		(at 41.8592 -28.6512 180)
		(property "Reference" "C180"
			(at 0 0 180)
			(layer "F.SilkS")
			(hide yes)
			(effects
				(font
					(size 1.27 1.27)
				)
			)
		)
		(property "Value" ""
			(at 0 0 180)
			(layer "F.Fab")
			(effects
				(font
					(size 1.27 1.27)
				)
			)
		)
		(duplicate_pad_numbers_are_jumpers no)
		(fp_line
			(start 0.7874 0.4064)
			(end -0.7874 0.4064)
			(stroke
				(width 0.1524)
				(type default)
			)
			(layer "F.SilkS")
		)
		(fp_line
			(start 0.7874 -0.4064)
			(end 0.7874 0.4064)
			(stroke
				(width 0.1524)
				(type default)
			)
			(layer "F.SilkS")
		)
		(fp_line
			(start -0.7874 0.4064)
			(end -0.7874 -0.4064)
			(stroke
				(width 0.1524)
				(type default)
			)
			(layer "F.SilkS")
		)
		(fp_line
			(start -0.7874 -0.4064)
			(end 0.7874 -0.4064)
			(stroke
				(width 0.1524)
				(type default)
			)
			(layer "F.SilkS")
		)
		(fp_line
			(start 0.67945 0.3048)
			(end 0.120396 0.3048)
			(stroke
				(width 0.1)
				(type default)
			)
			(layer "F.Fab")
		)
		(fp_line
			(start 0.67945 -0.3048)
			(end 0.67945 0.3048)
			(stroke
				(width 0.1)
				(type default)
			)
			(layer "F.Fab")
		)
		(fp_line
			(start 0.12065 -0.2794)
			(end 0.12065 -0.3048)
			(stroke
				(width 0.1)
				(type default)
			)
			(layer "F.Fab")
		)
		(fp_line
			(start 0.12065 -0.3048)
			(end 0.67945 -0.3048)
			(stroke
				(width 0.1)
				(type default)
			)
			(layer "F.Fab")
		)
		(fp_line
			(start 0.120396 0.3048)
			(end 0.120396 0.2794)
			(stroke
				(width 0.1)
				(type default)
			)
			(layer "F.Fab")
		)
		(fp_line
			(start 0.120396 0.2794)
			(end -0.12065 0.2794)
			(stroke
				(width 0.1)
				(type default)
			)
			(layer "F.Fab")
		)
		(fp_line
			(start -0.12065 0.3048)
			(end -0.67945 0.3048)
			(stroke
				(width 0.1)
				(type default)
			)
			(layer "F.Fab")
		)
		(fp_line
			(start -0.12065 0.2794)
			(end -0.12065 0.3048)
			(stroke
				(width 0.1)
				(type default)
			)
			(layer "F.Fab")
		)
		(fp_line
			(start -0.12065 -0.2794)
			(end 0.12065 -0.2794)
			(stroke
				(width 0.1)
				(type default)
			)
			(layer "F.Fab")
		)
		(fp_line
			(start -0.12065 -0.305054)
			(end -0.12065 -0.2794)
			(stroke
				(width 0.1)
				(type default)
			)
			(layer "F.Fab")
		)
		(fp_line
			(start -0.67945 0.3048)
			(end -0.67945 -0.305054)
			(stroke
				(width 0.1)
				(type default)
			)
			(layer "F.Fab")
		)
		(fp_line
			(start -0.67945 -0.305054)
			(end -0.12065 -0.305054)
			(stroke
				(width 0.1)
				(type default)
			)
			(layer "F.Fab")
		)
		(pad "1" smd circle
			(at -0.40005 0 180)
			(size 0 0)
			(layers "F.Cu" "F.Mask" "F.Paste")
			(net "P3V3_LDO")
		)
		(pad "2" smd circle
			(at 0.40005 0 180)
			(size 0 0)
			(layers "F.Cu" "F.Mask" "F.Paste")
			(net "GND")
		)
	)
)
